# T6G (Grand Teton) — schematic netlist excerpt (pin names and nets, part order shuffled) for the footprints in the layout excerpt that follows; sources: Cadence DE-HDL packaged netlist, KiCad conversion of 04192023_DAF0TMB3IC0_F0TG_MB_C_brd_V02_OCP.brd

C1086  Q_CAP  0.1UF 25V 10% X7R  pkg 0402  page 258 : A = P1V2_AUX_ADC_TIC ; B = GND
C2264  Q_CAP  22UF 4V 20% X6S  pkg C0402  page 72 : A = PVDDCR_SOC_P1 ; B = GND
C6601  Q_CAP_DIFFBUS  DIFF BUS_0.22UF 6.3V 20% X6S  pkg C0201  page 308 : \1\ = P5E_CPU0_P3_TX_BUF_C_DP<2> ; \2\ = P5E_CPU0_P3_TX_BUF_DP<2>

(kicad_pcb
	(version 20260206)
	(generator "pcbnew")
	(generator_version "10.0")
	(general
		(thickness 1.6)
		(legacy_teardrops no)
	)
	(paper "A4")
	(title_block
		(title "04192023_DAF0TMB3IC0_F0TG_MB_C_brd_V02_OCP.brd")
		(comment 1 "Grand Teton / footprints 6549-6551 of 8354")
	)
	(layers
		(0 "F.Cu" signal "TOP")
		(4 "In1.Cu" signal "GND")
		(6 "In2.Cu" signal "IN1")
		(8 "In3.Cu" signal "GND1")
		(10 "In4.Cu" signal "IN2")
		(12 "In5.Cu" signal "GND2")
		(14 "In6.Cu" signal "IN3")
		(16 "In7.Cu" signal "GND3")
		(18 "In8.Cu" signal "VCC")
		(20 "In9.Cu" signal "VCC1")
		(22 "In10.Cu" signal "GND4")
		(24 "In11.Cu" signal "IN4")
		(26 "In12.Cu" signal "GND5")
		(28 "In13.Cu" signal "IN5")
		(30 "In14.Cu" signal "GND6")
		(32 "In15.Cu" signal "IN6")
		(34 "In16.Cu" signal "GND7")
		(2 "B.Cu" signal "BOTTOM")
		(9 "F.Adhes" user "F.Adhesive")
		(11 "B.Adhes" user "B.Adhesive")
		(13 "F.Paste" user "Package Geometry/Pastemask Top")
		(15 "B.Paste" user "Package Geometry/Pastemask Bottom")
		(5 "F.SilkS" user "Ref Des/Silkscreen Top")
		(7 "B.SilkS" user "Ref Des/Silkscreen Bottom")
		(1 "F.Mask" user "Board Geometry/Soldermask Top")
		(3 "B.Mask" user "Board Geometry/Soldermask Bottom")
		(17 "Dwgs.User" user "User.Drawings")
		(19 "Cmts.User" user "User.Comments")
		(21 "Eco1.User" user "User.Eco1")
		(23 "Eco2.User" user "User.Eco2")
		(25 "Edge.Cuts" user "Board Geometry/Outline")
		(27 "Margin" user)
		(31 "F.CrtYd" user "Package Geometry/Place Bound Top")
		(29 "B.CrtYd" user "Package Geometry/Place Bound Bottom")
		(35 "F.Fab" user "Ref Des/Assembly Top")
		(33 "B.Fab" user "Ref Des/Assembly Bottom")
	)
	(footprint ""
		(layer "B.Cu")
		(at 228.4857 -324.349872 180)
		(property "Reference" "C1086"
			(at 0 0 0)
			(layer "B.SilkS")
			(hide yes)
			(effects
				(font
					(size 1.27 1.27)
				)
				(justify mirror)
			)
		)
		(property "Value" ""
			(at 0 0 0)
			(layer "B.Fab")
			(effects
				(font
					(size 1.27 1.27)
				)
				(justify mirror)
			)
		)
		(duplicate_pad_numbers_are_jumpers no)
		(fp_line
			(start 0.7874 0.4064)
			(end 0.7874 -0.4064)
			(stroke
				(width 0.1524)
				(type default)
			)
			(layer "B.SilkS")
		)
		(fp_line
			(start 0.7874 -0.4064)
			(end -0.7874 -0.4064)
			(stroke
				(width 0.1524)
				(type default)
			)
			(layer "B.SilkS")
		)
		(fp_line
			(start -0.7874 0.4064)
			(end 0.7874 0.4064)
			(stroke
				(width 0.1524)
				(type default)
			)
			(layer "B.SilkS")
		)
		(fp_line
			(start -0.7874 -0.4064)
			(end -0.7874 0.4064)
			(stroke
				(width 0.1524)
				(type default)
			)
			(layer "B.SilkS")
		)
		(fp_line
			(start 0.67945 0.3048)
			(end 0.67945 -0.305054)
			(stroke
				(width 0.1)
				(type default)
			)
			(layer "B.Fab")
		)
		(fp_line
			(start 0.67945 -0.305054)
			(end 0.12065 -0.305054)
			(stroke
				(width 0.1)
				(type default)
			)
			(layer "B.Fab")
		)
		(fp_line
			(start 0.12065 0.3048)
			(end 0.67945 0.3048)
			(stroke
				(width 0.1)
				(type default)
			)
			(layer "B.Fab")
		)
		(fp_line
			(start 0.12065 0.2794)
			(end 0.12065 0.3048)
			(stroke
				(width 0.1)
				(type default)
			)
			(layer "B.Fab")
		)
		(fp_line
			(start 0.12065 -0.2794)
			(end -0.12065 -0.2794)
			(stroke
				(width 0.1)
				(type default)
			)
			(layer "B.Fab")
		)
		(fp_line
			(start 0.12065 -0.305054)
			(end 0.12065 -0.2794)
			(stroke
				(width 0.1)
				(type default)
			)
			(layer "B.Fab")
		)
		(fp_line
			(start -0.120396 0.3048)
			(end -0.120396 0.2794)
			(stroke
				(width 0.1)
				(type default)
			)
			(layer "B.Fab")
		)
		(fp_line
			(start -0.120396 0.2794)
			(end 0.12065 0.2794)
			(stroke
				(width 0.1)
				(type default)
			)
			(layer "B.Fab")
		)
		(fp_line
			(start -0.12065 -0.2794)
			(end -0.12065 -0.3048)
			(stroke
				(width 0.1)
				(type default)
			)
			(layer "B.Fab")
		)
		(fp_line
			(start -0.12065 -0.3048)
			(end -0.67945 -0.3048)
			(stroke
				(width 0.1)
				(type default)
			)
			(layer "B.Fab")
		)
		(fp_line
			(start -0.67945 0.3048)
			(end -0.120396 0.3048)
			(stroke
				(width 0.1)
				(type default)
			)
			(layer "B.Fab")
		)
		(fp_line
			(start -0.67945 -0.3048)
			(end -0.67945 0.3048)
			(stroke
				(width 0.1)
				(type default)
			)
			(layer "B.Fab")
		)
		(pad "1" smd circle
			(at 0.40005 0)
			(size 0 0)
			(layers "B.Cu" "B.Mask" "B.Paste")
			(net "P1V2_AUX_ADC_TIC")
		)
		(pad "2" smd circle
			(at -0.40005 0)
			(size 0 0)
			(layers "B.Cu" "B.Mask" "B.Paste")
			(net "GND")
		)
	)
	(footprint ""
		(layer "B.Cu")
		(at 113.105946 -257.74523 180)
		(property "Reference" "C2264"
			(at 0 0 0)
			(layer "B.SilkS")
			(hide yes)
			(effects
				(font
					(size 1.27 1.27)
				)
				(justify mirror)
			)
		)
		(property "Value" ""
			(at 0 0 0)
			(layer "B.Fab")
			(effects
				(font
					(size 1.27 1.27)
				)
				(justify mirror)
			)
		)
		(duplicate_pad_numbers_are_jumpers no)
		(fp_line
			(start 0.7874 0.4064)
			(end 0.7874 -0.4064)
			(stroke
				(width 0.1524)
				(type default)
			)
			(layer "B.SilkS")
		)
		(fp_line
			(start 0.7874 -0.4064)
			(end -0.7874 -0.4064)
			(stroke
				(width 0.1524)
				(type default)
			)
			(layer "B.SilkS")
		)
		(fp_line
			(start -0.7874 0.4064)
			(end 0.7874 0.4064)
			(stroke
				(width 0.1524)
				(type default)
			)
			(layer "B.SilkS")
		)
		(fp_line
			(start -0.7874 -0.4064)
			(end -0.7874 0.4064)
			(stroke
				(width 0.1524)
				(type default)
			)
			(layer "B.SilkS")
		)
		(fp_line
			(start 0.67945 0.3048)
			(end 0.67945 -0.305054)
			(stroke
				(width 0.1)
				(type default)
			)
			(layer "B.Fab")
		)
		(fp_line
			(start 0.67945 -0.305054)
			(end 0.12065 -0.305054)
			(stroke
				(width 0.1)
				(type default)
			)
			(layer "B.Fab")
		)
		(fp_line
			(start 0.12065 0.3048)
			(end 0.67945 0.3048)
			(stroke
				(width 0.1)
				(type default)
			)
			(layer "B.Fab")
		)
		(fp_line
			(start 0.12065 0.2794)
			(end 0.12065 0.3048)
			(stroke
				(width 0.1)
				(type default)
			)
			(layer "B.Fab")
		)
		(fp_line
			(start 0.12065 -0.2794)
			(end -0.12065 -0.2794)
			(stroke
				(width 0.1)
				(type default)
			)
			(layer "B.Fab")
		)
		(fp_line
			(start 0.12065 -0.305054)
			(end 0.12065 -0.2794)
			(stroke
				(width 0.1)
				(type default)
			)
			(layer "B.Fab")
		)
		(fp_line
			(start -0.120396 0.3048)
			(end -0.120396 0.2794)
			(stroke
				(width 0.1)
				(type default)
			)
			(layer "B.Fab")
		)
		(fp_line
			(start -0.120396 0.2794)
			(end 0.12065 0.2794)
			(stroke
				(width 0.1)
				(type default)
			)
			(layer "B.Fab")
		)
		(fp_line
			(start -0.12065 -0.2794)
			(end -0.12065 -0.3048)
			(stroke
				(width 0.1)
				(type default)
			)
			(layer "B.Fab")
		)
		(fp_line
			(start -0.12065 -0.3048)
			(end -0.67945 -0.3048)
			(stroke
				(width 0.1)
				(type default)
			)
			(layer "B.Fab")
		)
		(fp_line
			(start -0.67945 0.3048)
			(end -0.120396 0.3048)
			(stroke
				(width 0.1)
				(type default)
			)
			(layer "B.Fab")
		)
		(fp_line
			(start -0.67945 -0.3048)
			(end -0.67945 0.3048)
			(stroke
				(width 0.1)
				(type default)
			)
			(layer "B.Fab")
		)
		(pad "1" smd circle
			(at 0.40005 0)
			(size 0 0)
			(layers "B.Cu" "B.Mask" "B.Paste")
			(net "PVDDCR_SOC_P1")
		)
		(pad "2" smd circle
			(at -0.40005 0)
			(size 0 0)
			(layers "B.Cu" "B.Mask" "B.Paste")
			(net "GND")
		)
	)
	(footprint ""
		(layer "B.Cu")
		(at 379.441202 -416.899344 90)
		(property "Reference" "C6601"
			(at 0 0 90)
			(layer "B.SilkS")
			(hide yes)
			(effects
				(font
					(size 1.27 1.27)
				)
				(justify mirror)
			)
		)
		(property "Value" ""
			(at 0 0 90)
			(layer "B.Fab")
			(effects
				(font
					(size 1.27 1.27)
				)
				(justify mirror)
			)
		)
		(duplicate_pad_numbers_are_jumpers no)
		(fp_line
			(start 0.299974 -0.150114)
			(end -0.299974 -0.150114)
			(stroke
				(width 0.1)
				(type default)
			)
			(layer "B.Fab")
		)
		(fp_line
			(start -0.299974 -0.150114)
			(end -0.299974 0.150114)
			(stroke
				(width 0.1)
				(type default)
			)
			(layer "B.Fab")
		)
		(fp_line
			(start 0.299974 0.150114)
			(end 0.299974 -0.150114)
			(stroke
				(width 0.1)
				(type default)
			)
			(layer "B.Fab")
		)
		(fp_line
			(start -0.299974 0.150114)
			(end 0.299974 0.150114)
			(stroke
				(width 0.1)
				(type default)
			)
			(layer "B.Fab")
		)
		(pad "1" smd rect
			(at 0.2667 0 270)
			(size 0.3048 0.381)
			(layers "B.Cu" "B.Mask" "B.Paste")
			(net "P5E_CPU0_P3_TX_BUF_C_DP<2>")
		)
		(pad "2" smd rect
			(at -0.2667 0 270)
			(size 0.3048 0.381)
			(layers "B.Cu" "B.Mask" "B.Paste")
			(net "P5E_CPU0_P3_TX_BUF_DP<2>")
		)
	)
)
